(kicad_pcb
	(version 20260206)
	(generator "pcbnew")
	(generator_version "10.0")
	(general
		(thickness 1.6)
		(legacy_teardrops no)
	)
	(paper "A4")
	(title_block
		(title "Bryce Canyon_R.DPB_16317-1_OCP.brd")
		(comment 1 "Bryce Canyon / footprints 712-718 of 2099")
	)
	(layers
		(0 "F.Cu" signal "TOP")
		(4 "In1.Cu" signal "L2GND")
		(6 "In2.Cu" signal "L3")
		(8 "In3.Cu" signal "L4VCC")
		(10 "In4.Cu" signal "L5VCC")
		(12 "In5.Cu" signal "L6")
		(14 "In6.Cu" signal "L7GND")
		(2 "B.Cu" signal "BOTTOM")
		(9 "F.Adhes" user "F.Adhesive")
		(11 "B.Adhes" user "B.Adhesive")
		(13 "F.Paste" user "Package Geometry/Pastemask Top")
		(15 "B.Paste" user "Package Geometry/Pastemask Bottom")
		(5 "F.SilkS" user "Ref Des/Silkscreen Top")
		(7 "B.SilkS" user "Ref Des/Silkscreen Bottom")
		(1 "F.Mask" user "Board Geometry/Soldermask Top")
		(3 "B.Mask" user "Board Geometry/Soldermask Bottom")
		(17 "Dwgs.User" user "User.Drawings")
		(19 "Cmts.User" user "User.Comments")
		(21 "Eco1.User" user "User.Eco1")
		(23 "Eco2.User" user "User.Eco2")
		(25 "Edge.Cuts" user "Board Geometry/Outline")
		(27 "Margin" user)
		(31 "F.CrtYd" user "Package Geometry/Place Bound Top")
		(29 "B.CrtYd" user "Package Geometry/Place Bound Bottom")
		(35 "F.Fab" user "Ref Des/Assembly Top")
		(33 "B.Fab" user "Ref Des/Assembly Bottom")
	)
	(footprint ""
		(layer "F.Cu")
		(at 248.285 -311.15 -90)
		(property "Reference" "R1086"
			(at 0 0 270)
			(layer "F.SilkS")
			(hide yes)
			(effects
				(font
					(size 1.27 1.27)
				)
			)
		)
		(property "Value" "4K7R2F-GP"
			(at 0.064008 -3.993896 270)
			(unlocked yes)
			(layer "F.Fab")
			(hide yes)
			(effects
				(font
					(size 1.016 1.016)
					(thickness 0.1524)
				)
			)
		)
		(property "Device Type" "R402H16"
			(at 0.064008 -5.517896 270)
			(unlocked yes)
			(layer "F.Fab")
			(hide yes)
			(effects
				(font
					(size 1.016 1.016)
					(thickness 0.1524)
				)
			)
		)
		(duplicate_pad_numbers_are_jumpers no)
		(fp_line
			(start -0.508 -0.9398)
			(end -0.508 0.9398)
			(stroke
				(width 0.1524)
				(type default)
			)
			(layer "F.SilkS")
		)
		(fp_line
			(start 0.508 -0.9398)
			(end -0.508 -0.9398)
			(stroke
				(width 0.1524)
				(type default)
			)
			(layer "F.SilkS")
		)
		(fp_rect
			(start -0.508 0.9398)
			(end 0.508 -0.9398)
			(stroke
				(width 0)
				(type default)
			)
			(fill no)
			(layer "F.CrtYd")
		)
		(fp_rect
			(start -0.508 0.9398)
			(end 0.508 -0.9398)
			(stroke
				(width 0)
				(type default)
			)
			(fill no)
			(layer "F.Fab")
		)
		(pad "1" smd custom
			(at 0 -0.4445 270)
			(size 0.1397 0.1397)
			(layers "F.Cu" "F.Mask" "F.Paste")
			(net "P3V3_STBY_A")
			(options
				(clearance outline)
				(anchor circle)
			)
			(primitives
				(gr_poly
					(pts
						(arc
							(start -0.1778 -0.2794)
							(mid -0.249642 -0.249642)
							(end -0.2794 -0.1778)
						)
						(arc
							(start -0.2794 0.1778)
							(mid -0.249642 0.249642)
							(end -0.1778 0.2794)
						)
						(arc
							(start 0.1778 0.2794)
							(mid 0.249642 0.249642)
							(end 0.2794 0.1778)
						)
						(arc
							(start 0.2794 -0.1778)
							(mid 0.249642 -0.249642)
							(end 0.1778 -0.2794)
						)
					)
					(width 0)
					(fill yes)
				)
			)
		)
		(pad "2" smd custom
			(at 0 0.4445 270)
			(size 0.1397 0.1397)
			(layers "F.Cu" "F.Mask" "F.Paste")
			(net "MAX31790_A_FULL_SPEED")
			(options
				(clearance outline)
				(anchor circle)
			)
			(primitives
				(gr_poly
					(pts
						(arc
							(start -0.1778 -0.2794)
							(mid -0.249642 -0.249642)
							(end -0.2794 -0.1778)
						)
						(arc
							(start -0.2794 0.1778)
							(mid -0.249642 0.249642)
							(end -0.1778 0.2794)
						)
						(arc
							(start 0.1778 0.2794)
							(mid 0.249642 0.249642)
							(end 0.2794 0.1778)
						)
						(arc
							(start 0.2794 -0.1778)
							(mid 0.249642 -0.249642)
							(end 0.1778 -0.2794)
						)
					)
					(width 0)
					(fill yes)
				)
			)
		)
	)
	(footprint ""
		(layer "F.Cu")
		(at 143.129 -17.653 180)
		(property "Reference" "D28"
			(at 0 0 180)
			(layer "F.SilkS")
			(hide yes)
			(effects
				(font
					(size 1.27 1.27)
				)
			)
		)
		(property "Value" "RB551V30-GP"
			(at 0 -6.7818 180)
			(unlocked yes)
			(layer "F.Fab")
			(hide yes)
			(effects
				(font
					(size 1.016 1.016)
					(thickness 0.1524)
				)
			)
		)
		(property "Device Type" "SOD323AKH38"
			(at 0 -8.6868 180)
			(unlocked yes)
			(layer "F.Fab")
			(hide yes)
			(effects
				(font
					(size 1.016 1.016)
					(thickness 0.1524)
				)
			)
		)
		(duplicate_pad_numbers_are_jumpers no)
		(fp_line
			(start 0.889 2.159)
			(end -0.889 2.159)
			(stroke
				(width 0.1524)
				(type default)
			)
			(layer "F.SilkS")
		)
		(fp_line
			(start 0.889 -1.9304)
			(end 0.889 2.159)
			(stroke
				(width 0.1524)
				(type default)
			)
			(layer "F.SilkS")
		)
		(fp_line
			(start 0.762 2.0574)
			(end -0.762 2.0574)
			(stroke
				(width 0.508)
				(type default)
			)
			(layer "F.SilkS")
		)
		(fp_line
			(start -0.889 2.159)
			(end -0.889 -1.9304)
			(stroke
				(width 0.1524)
				(type default)
			)
			(layer "F.SilkS")
		)
		(fp_line
			(start -0.889 -1.9304)
			(end 0.889 -1.9304)
			(stroke
				(width 0.1524)
				(type default)
			)
			(layer "F.SilkS")
		)
		(fp_rect
			(start -1.016 2.3114)
			(end 1.016 -2.0066)
			(stroke
				(width 0)
				(type default)
			)
			(fill no)
			(layer "F.CrtYd")
		)
		(fp_poly
			(pts
				(xy -1.016 -2.0066) (xy 1.016 -2.0066) (xy 1.016 2.3114) (xy -1.016 2.3114)
			)
			(stroke
				(width 0)
				(type default)
			)
			(fill no)
			(layer "F.Fab")
		)
		(pad "A" smd rect
			(at 0 -1.143 180)
			(size 0.5588 1.016)
			(layers "F.Cu" "F.Mask" "F.Paste")
			(net "SW_HDD_R28")
		)
		(pad "K" smd rect
			(at 0 1.143 180)
			(size 0.5588 1.016)
			(layers "F.Cu" "F.Mask" "F.Paste")
			(net "SW_HDD_N28")
		)
	)
	(footprint ""
		(layer "F.Cu")
		(at 264.2997 -375.999756 90)
		(property "Reference" "R1062"
			(at 0 0 90)
			(layer "F.SilkS")
			(hide yes)
			(effects
				(font
					(size 1.27 1.27)
				)
			)
		)
		(property "Value" "4K7R3J-2-GP"
			(at -0.0254 -2.5146 90)
			(unlocked yes)
			(layer "F.Fab")
			(hide yes)
			(effects
				(font
					(size 1.016 1.016)
					(thickness 0.1524)
				)
			)
		)
		(property "Device Type" "R603H22"
			(at -0.0254 -4.0386 90)
			(unlocked yes)
			(layer "F.Fab")
			(hide yes)
			(effects
				(font
					(size 1.016 1.016)
					(thickness 0.1524)
				)
			)
		)
		(duplicate_pad_numbers_are_jumpers no)
		(fp_line
			(start 0.2032 0)
			(end 0.4826 0)
			(stroke
				(width 0.2032)
				(type default)
			)
			(layer "F.SilkS")
		)
		(fp_line
			(start -0.4826 0)
			(end -0.2032 0)
			(stroke
				(width 0.2032)
				(type default)
			)
			(layer "F.SilkS")
		)
		(fp_rect
			(start -0.5842 1.3335)
			(end 0.5842 -1.3335)
			(stroke
				(width 0)
				(type default)
			)
			(fill no)
			(layer "F.CrtYd")
		)
		(fp_rect
			(start -0.5842 1.3335)
			(end 0.5842 -1.3335)
			(stroke
				(width 0)
				(type default)
			)
			(fill no)
			(layer "F.Fab")
		)
		(pad "1" smd custom
			(at 0 -0.762 90)
			(size 0.2159 0.2159)
			(layers "F.Cu" "F.Mask" "F.Paste")
			(net "P3V3_IN")
			(options
				(clearance outline)
				(anchor circle)
			)
			(primitives
				(gr_poly
					(pts
						(arc
							(start -0.3302 -0.4318)
							(mid -0.402042 -0.402042)
							(end -0.4318 -0.3302)
						)
						(arc
							(start -0.4318 0.3302)
							(mid -0.402042 0.402042)
							(end -0.3302 0.4318)
						)
						(arc
							(start 0.3302 0.4318)
							(mid 0.402042 0.402042)
							(end 0.4318 0.3302)
						)
						(arc
							(start 0.4318 -0.3302)
							(mid 0.402042 -0.402042)
							(end 0.3302 -0.4318)
						)
					)
					(width 0)
					(fill yes)
				)
			)
		)
		(pad "2" smd custom
			(at 0 0.762 90)
			(size 0.2159 0.2159)
			(layers "F.Cu" "F.Mask" "F.Paste")
			(net "IR_SWITCH_C")
			(options
				(clearance outline)
				(anchor circle)
			)
			(primitives
				(gr_poly
					(pts
						(arc
							(start -0.3302 -0.4318)
							(mid -0.402042 -0.402042)
							(end -0.4318 -0.3302)
						)
						(arc
							(start -0.4318 0.3302)
							(mid -0.402042 0.402042)
							(end -0.3302 0.4318)
						)
						(arc
							(start 0.3302 0.4318)
							(mid 0.402042 0.402042)
							(end 0.4318 0.3302)
						)
						(arc
							(start 0.4318 -0.3302)
							(mid 0.402042 -0.402042)
							(end 0.3302 -0.4318)
						)
					)
					(width 0)
					(fill yes)
				)
			)
		)
	)
	(footprint ""
		(layer "F.Cu")
		(at 49.349914 -65.39992)
		(property "Reference" "LED14"
			(at 0 0 0)
			(layer "F.SilkS")
			(hide yes)
			(effects
				(font
					(size 1.27 1.27)
				)
			)
		)
		(property "Value" "LED-BY-19-GP"
			(at -2.132076 1.414018 0)
			(unlocked yes)
			(layer "F.Fab")
			(hide yes)
			(effects
				(font
					(size 1.016 1.016)
					(thickness 0.1524)
				)
			)
		)
		(property "Device Type" "LED-1615-4PH26"
			(at -2.132076 -0.109982 0)
			(unlocked yes)
			(layer "F.Fab")
			(hide yes)
			(effects
				(font
					(size 1.016 1.016)
					(thickness 0.1524)
				)
			)
		)
		(duplicate_pad_numbers_are_jumpers no)
		(fp_line
			(start -1.2954 0.254)
			(end -1.2954 1.6002)
			(stroke
				(width 0.508)
				(type default)
			)
			(layer "F.SilkS")
		)
		(fp_line
			(start -1.2954 1.6002)
			(end 1.2954 1.6002)
			(stroke
				(width 0.508)
				(type default)
			)
			(layer "F.SilkS")
		)
		(fp_line
			(start -1.1176 -1.4224)
			(end 1.1176 -1.4224)
			(stroke
				(width 0.1524)
				(type default)
			)
			(layer "F.SilkS")
		)
		(fp_line
			(start -1.1176 1.4224)
			(end -1.1176 -1.4224)
			(stroke
				(width 0.1524)
				(type default)
			)
			(layer "F.SilkS")
		)
		(fp_line
			(start 1.1176 -1.4224)
			(end 1.1176 1.4224)
			(stroke
				(width 0.1524)
				(type default)
			)
			(layer "F.SilkS")
		)
		(fp_line
			(start 1.1176 1.4224)
			(end -1.1176 1.4224)
			(stroke
				(width 0.1524)
				(type default)
			)
			(layer "F.SilkS")
		)
		(fp_line
			(start 1.2954 1.6002)
			(end 1.2954 0.254)
			(stroke
				(width 0.508)
				(type default)
			)
			(layer "F.SilkS")
		)
		(fp_rect
			(start -0.7493 0.8001)
			(end 0.7493 -0.8001)
			(stroke
				(width 0)
				(type default)
			)
			(fill no)
			(layer "F.CrtYd")
		)
		(fp_poly
			(pts
				(xy -1.3716 1.6764) (xy -1.3716 -1.6764) (xy 1.3716 -1.6764) (xy 1.3716 0.0635) (xy 0.7493 0.0635)
				(xy 0.7493 -0.8001) (xy -0.7493 -0.8001) (xy -0.7493 0.8001) (xy 0.7493 0.8001) (xy 0.7493 0.0762)
				(xy 1.3716 0.0762) (xy 1.3716 1.6764)
			)
			(stroke
				(width 0)
				(type default)
			)
			(fill no)
			(layer "F.CrtYd")
		)
		(fp_rect
			(start -1.3716 1.6764)
			(end 1.3716 -1.6764)
			(stroke
				(width 0)
				(type default)
			)
			(fill no)
			(layer "F.Fab")
		)
		(pad "1" smd rect
			(at 0.50038 -0.73025)
			(size 0.7112 0.8636)
			(layers "F.Cu" "F.Mask" "F.Paste")
			(net "DRV_ACT_13")
		)
		(pad "2" smd rect
			(at -0.50038 -0.73025)
			(size 0.7112 0.8636)
			(layers "F.Cu" "F.Mask" "F.Paste")
			(net "FLT_HDD13")
		)
		(pad "3" smd rect
			(at 0.50038 0.73025)
			(size 0.7112 0.8636)
			(layers "F.Cu" "F.Mask" "F.Paste")
			(net "DRV_ACT_13_N")
		)
		(pad "4" smd rect
			(at -0.50038 0.73025)
			(size 0.7112 0.8636)
			(layers "F.Cu" "F.Mask" "F.Paste")
			(net "FLT_HDD13_N")
		)
	)
	(footprint ""
		(layer "F.Cu")
		(at 240.687098 -132.685028)
		(property "Reference" "R420"
			(at 0 0 0)
			(layer "F.SilkS")
			(hide yes)
			(effects
				(font
					(size 1.27 1.27)
				)
			)
		)
		(property "Value" "0R2J-2-GP"
			(at 0.064008 -3.993896 0)
			(unlocked yes)
			(layer "F.Fab")
			(hide yes)
			(effects
				(font
					(size 1.016 1.016)
					(thickness 0.1524)
				)
			)
		)
		(property "Device Type" "R402H16"
			(at 0.064008 -5.517896 0)
			(unlocked yes)
			(layer "F.Fab")
			(hide yes)
			(effects
				(font
					(size 1.016 1.016)
					(thickness 0.1524)
				)
			)
		)
		(duplicate_pad_numbers_are_jumpers no)
		(fp_line
			(start -0.508 -0.9398)
			(end -0.508 0.9398)
			(stroke
				(width 0.1524)
				(type default)
			)
			(layer "F.SilkS")
		)
		(fp_line
			(start 0.508 -0.9398)
			(end -0.508 -0.9398)
			(stroke
				(width 0.1524)
				(type default)
			)
			(layer "F.SilkS")
		)
		(fp_rect
			(start -0.508 0.9398)
			(end 0.508 -0.9398)
			(stroke
				(width 0)
				(type default)
			)
			(fill no)
			(layer "F.CrtYd")
		)
		(fp_rect
			(start -0.508 0.9398)
			(end 0.508 -0.9398)
			(stroke
				(width 0)
				(type default)
			)
			(fill no)
			(layer "F.Fab")
		)
		(pad "1" smd custom
			(at 0 -0.4445)
			(size 0.1397 0.1397)
			(layers "F.Cu" "F.Mask" "F.Paste")
			(net "I2C_DPB_B_SCL_BUF")
			(options
				(clearance outline)
				(anchor circle)
			)
			(primitives
				(gr_poly
					(pts
						(arc
							(start -0.1778 -0.2794)
							(mid -0.249642 -0.249642)
							(end -0.2794 -0.1778)
						)
						(arc
							(start -0.2794 0.1778)
							(mid -0.249642 0.249642)
							(end -0.1778 0.2794)
						)
						(arc
							(start 0.1778 0.2794)
							(mid 0.249642 0.249642)
							(end 0.2794 0.1778)
						)
						(arc
							(start 0.2794 -0.1778)
							(mid 0.249642 -0.249642)
							(end 0.1778 -0.2794)
						)
					)
					(width 0)
					(fill yes)
				)
			)
		)
		(pad "2" smd custom
			(at 0 0.4445)
			(size 0.1397 0.1397)
			(layers "F.Cu" "F.Mask" "F.Paste")
			(net "I2C_DPB_B_SCL")
			(options
				(clearance outline)
				(anchor circle)
			)
			(primitives
				(gr_poly
					(pts
						(arc
							(start -0.1778 -0.2794)
							(mid -0.249642 -0.249642)
							(end -0.2794 -0.1778)
						)
						(arc
							(start -0.2794 0.1778)
							(mid -0.249642 0.249642)
							(end -0.1778 0.2794)
						)
						(arc
							(start 0.1778 0.2794)
							(mid 0.249642 0.249642)
							(end 0.2794 0.1778)
						)
						(arc
							(start 0.2794 -0.1778)
							(mid 0.249642 -0.249642)
							(end 0.1778 -0.2794)
						)
					)
					(width 0)
					(fill yes)
				)
			)
		)
	)
	(footprint ""
		(layer "F.Cu")
		(at 479.384614 -130.21945 -90)
		(property "Reference" "C327"
			(at 0 0 270)
			(layer "F.SilkS")
			(hide yes)
			(effects
				(font
					(size 1.27 1.27)
				)
			)
		)
		(property "Value" "SCD01U16V1KX-GP"
			(at -2.8321 -1.7399 270)
			(unlocked yes)
			(layer "F.Fab")
			(hide yes)
			(effects
				(font
					(size 1.016 1.016)
					(thickness 0.1524)
				)
			)
		)
		(property "Device Type" "C0201H13"
			(at -2.8321 -3.2639 270)
			(unlocked yes)
			(layer "F.Fab")
			(hide yes)
			(effects
				(font
					(size 1.016 1.016)
					(thickness 0.1524)
				)
			)
		)
		(duplicate_pad_numbers_are_jumpers no)
		(fp_rect
			(start -0.2794 0.6477)
			(end 0.2794 -0.6477)
			(stroke
				(width 0)
				(type default)
			)
			(fill no)
			(layer "F.CrtYd")
		)
		(fp_rect
			(start -0.2794 0.6477)
			(end 0.2794 -0.6477)
			(stroke
				(width 0)
				(type default)
			)
			(fill no)
			(layer "F.Fab")
		)
		(pad "1" smd custom
			(at 0 -0.2794 270)
			(size 0.0762 0.0762)
			(layers "F.Cu" "F.Mask" "F.Paste")
			(net "SAS_HDD_RX_N23")
			(options
				(clearance outline)
				(anchor circle)
			)
			(primitives
				(gr_poly
					(pts
						(arc
							(start 0.1524 -0.127)
							(mid 0.137521 -0.162921)
							(end 0.1016 -0.1778)
						)
						(arc
							(start -0.1016 -0.1778)
							(mid -0.137521 -0.162921)
							(end -0.1524 -0.127)
						)
						(arc
							(start -0.1524 0.127)
							(mid -0.137521 0.162921)
							(end -0.1016 0.1778)
						)
						(arc
							(start 0.1016 0.1778)
							(mid 0.137521 0.162921)
							(end 0.1524 0.127)
						)
					)
					(width 0)
					(fill yes)
				)
			)
		)
		(pad "2" smd custom
			(at 0 0.2794 270)
			(size 0.0762 0.0762)
			(layers "F.Cu" "F.Mask" "F.Paste")
			(net "PHY_SCC_B_TO_DRV_B_23_DN")
			(options
				(clearance outline)
				(anchor circle)
			)
			(primitives
				(gr_poly
					(pts
						(arc
							(start 0.1524 -0.127)
							(mid 0.137521 -0.162921)
							(end 0.1016 -0.1778)
						)
						(arc
							(start -0.1016 -0.1778)
							(mid -0.137521 -0.162921)
							(end -0.1524 -0.127)
						)
						(arc
							(start -0.1524 0.127)
							(mid -0.137521 0.162921)
							(end -0.1016 0.1778)
						)
						(arc
							(start 0.1016 0.1778)
							(mid 0.137521 0.162921)
							(end 0.1524 0.127)
						)
					)
					(width 0)
					(fill yes)
				)
			)
		)
	)
	(footprint ""
		(layer "F.Cu")
		(at 334.899 -253.873 -90)
		(property "Reference" "Q22"
			(at 0 0 270)
			(layer "F.SilkS")
			(hide yes)
			(effects
				(font
					(size 1.27 1.27)
				)
			)
		)
		(property "Value" "AO4406AL-GP"
			(at -3.707384 -1.5367 270)
			(unlocked yes)
			(layer "F.Fab")
			(hide yes)
			(effects
				(font
					(size 1.016 1.016)
					(thickness 0.1524)
				)
			)
		)
		(property "Device Type" "SOIC8H69"
			(at -3.707384 -3.0607 270)
			(unlocked yes)
			(layer "F.Fab")
			(hide yes)
			(effects
				(font
					(size 1.016 1.016)
					(thickness 0.1524)
				)
			)
		)
		(duplicate_pad_numbers_are_jumpers no)
		(fp_line
			(start -2.6289 3.4417)
			(end -2.6289 1.4732)
			(stroke
				(width 0.381)
				(type default)
			)
			(layer "F.SilkS")
		)
		(fp_line
			(start -2.7432 1.4224)
			(end -2.6416 1.4224)
			(stroke
				(width 0.1524)
				(type default)
			)
			(layer "F.SilkS")
		)
		(fp_line
			(start -2.7432 1.4224)
			(end 2.1336 1.4224)
			(stroke
				(width 0.1524)
				(type default)
			)
			(layer "F.SilkS")
		)
		(fp_line
			(start 2.1336 1.4224)
			(end 2.1336 -1.4224)
			(stroke
				(width 0.1524)
				(type default)
			)
			(layer "F.SilkS")
		)
		(fp_line
			(start -2.1844 -0.0508)
			(end -2.7178 0.508)
			(stroke
				(width 0.1524)
				(type default)
			)
			(layer "F.SilkS")
		)
		(fp_line
			(start -2.7178 -0.508)
			(end -2.1844 -0.0508)
			(stroke
				(width 0.1524)
				(type default)
			)
			(layer "F.SilkS")
		)
		(fp_line
			(start -2.7432 -1.4224)
			(end -2.7432 1.4224)
			(stroke
				(width 0.1524)
				(type default)
			)
			(layer "F.SilkS")
		)
		(fp_line
			(start 2.1336 -1.4224)
			(end -2.7432 -1.4224)
			(stroke
				(width 0.1524)
				(type default)
			)
			(layer "F.SilkS")
		)
		(fp_poly
			(pts
				(xy -2.2098 -1.4224) (xy -2.2098 1.4224) (xy 2.2098 1.4224) (xy 2.2098 -1.4224)
			)
			(stroke
				(width 0)
				(type default)
			)
			(fill yes)
			(layer "F.SilkS")
		)
		(fp_rect
			(start -2.450084 2.999994)
			(end 2.450084 -2.999994)
			(stroke
				(width 0)
				(type default)
			)
			(fill no)
			(layer "F.CrtYd")
		)
		(fp_poly
			(pts
				(xy -2.8194 3.6322) (xy -2.8194 -3.6322) (xy 2.8194 -3.6322) (xy 2.8194 1.18364) (xy 2.450084 1.18364)
				(xy 2.450084 -2.999994) (xy -2.450084 -2.999994) (xy -2.450084 2.999994) (xy 2.450084 2.999994)
				(xy 2.450084 1.18618) (xy 2.8194 1.18618) (xy 2.8194 3.6322)
			)
			(stroke
				(width 0)
				(type default)
			)
			(fill no)
			(layer "F.CrtYd")
		)
		(fp_rect
			(start -2.8194 3.6322)
			(end 2.8194 -3.6322)
			(stroke
				(width 0)
				(type default)
			)
			(fill no)
			(layer "F.Fab")
		)
		(pad "1" smd rect
			(at -1.905 2.54 270)
			(size 0.635 1.651)
			(layers "F.Cu" "F.Mask" "F.Paste")
			(net "P5V_HDD6")
		)
		(pad "2" smd rect
			(at -0.635 2.54 270)
			(size 0.635 1.651)
			(layers "F.Cu" "F.Mask" "F.Paste")
			(net "P5V_HDD6")
		)
		(pad "3" smd rect
			(at 0.635 2.54 270)
			(size 0.635 1.651)
			(layers "F.Cu" "F.Mask" "F.Paste")
			(net "P5V_HDD6")
		)
		(pad "4" smd rect
			(at 1.905 2.54 270)
			(size 0.635 1.651)
			(layers "F.Cu" "F.Mask" "F.Paste")
			(net "SW_HDD_P6")
		)
		(pad "5" smd rect
			(at 1.905 -2.54 270)
			(size 0.635 1.651)
			(layers "F.Cu" "F.Mask" "F.Paste")
			(net "P5V_B_3")
		)
		(pad "6" smd rect
			(at 0.635 -2.54 270)
			(size 0.635 1.651)
			(layers "F.Cu" "F.Mask" "F.Paste")
			(net "P5V_B_3")
		)
		(pad "7" smd rect
			(at -0.635 -2.54 270)
			(size 0.635 1.651)
			(layers "F.Cu" "F.Mask" "F.Paste")
			(net "P5V_B_3")
		)
		(pad "8" smd rect
			(at -1.905 -2.54 270)
			(size 0.635 1.651)
			(layers "F.Cu" "F.Mask" "F.Paste")
			(net "P5V_B_3")
		)
	)
)
